(kicad_pcb
	(version 20241229)
	(generator "pcbnew")
	(generator_version "9.0")
	(general
		(thickness 1.294)
		(legacy_teardrops no)
	)
	(paper "A3")
	(title_block
		(title "Kintex 410T devboard")
		(date "2024-04-03")
		(rev "1.1.2")
		(comment 9 "footprints 391-396 of 975")
	)
	(layers
		(0 "F.Cu" mixed)
		(4 "In1.Cu" power)
		(6 "In2.Cu" power)
		(8 "In3.Cu" mixed)
		(10 "In4.Cu" power)
		(12 "In5.Cu" mixed)
		(14 "In6.Cu" power)
		(16 "In7.Cu" mixed)
		(18 "In8.Cu" power)
		(2 "B.Cu" mixed)
		(9 "F.Adhes" user "F.Adhesive")
		(11 "B.Adhes" user "B.Adhesive")
		(13 "F.Paste" user)
		(15 "B.Paste" user)
		(5 "F.SilkS" user "F.Silkscreen")
		(7 "B.SilkS" user "B.Silkscreen")
		(1 "F.Mask" user)
		(3 "B.Mask" user)
		(17 "Dwgs.User" user "User.Drawings")
		(19 "Cmts.User" user "User.Comments")
		(21 "Eco1.User" user "User.Eco1")
		(23 "Eco2.User" user "User.Eco2")
		(25 "Edge.Cuts" user)
		(27 "Margin" user)
		(31 "F.CrtYd" user "F.Courtyard")
		(29 "B.CrtYd" user "B.Courtyard")
		(35 "F.Fab" user)
		(33 "B.Fab" user)
	)
	(footprint "antmicro-footprints:R_Array_4x0201_Panasonic_EXB18V"
		(layer "F.Cu")
		(at 251.4 122)
		(property "Reference" "R27"
			(at 1.25 -0.8 0)
			(layer "F.SilkS")
			(effects
				(font
					(size 0.7 0.7)
					(thickness 0.15)
				)
				(justify right bottom)
			)
		)
		(property "Value" "R_4x33R_0201_array"
			(at -1.1 1.8 0)
			(layer "F.Fab")
			(effects
				(font
					(size 0.7 0.7)
					(thickness 0.15)
				)
				(justify left bottom)
			)
		)
		(property "Description" "Fixed Network Resistor, 33 ohm, Isolated, 4 Resistors, 0502 [1406 Metric], Flat, ± 5%"
			(at 0 0 0)
			(layer "F.Fab")
			(hide yes)
			(effects
				(font
					(size 1.27 1.27)
					(thickness 0.15)
				)
			)
		)
		(property "Author" "Antmicro"
			(at 0 0 0)
			(layer "F.Fab")
			(hide yes)
			(effects
				(font
					(size 1 1)
					(thickness 0.15)
				)
			)
		)
		(property "License" "Apache-2.0"
			(at 0 0 0)
			(layer "F.Fab")
			(hide yes)
			(effects
				(font
					(size 1 1)
					(thickness 0.15)
				)
			)
		)
		(property "MPN" "EXB-18V330JX"
			(at 0 0 0)
			(layer "F.Fab")
			(hide yes)
			(effects
				(font
					(size 1 1)
					(thickness 0.15)
				)
			)
		)
		(property "Manufacturer" "Panasonic"
			(at 0 0 0)
			(layer "F.Fab")
			(hide yes)
			(effects
				(font
					(size 1 1)
					(thickness 0.15)
				)
			)
		)
		(property "Val" "R_4x33R_0201"
			(at 0 0 0)
			(layer "F.Fab")
			(hide yes)
			(effects
				(font
					(size 1 1)
					(thickness 0.15)
				)
			)
		)
		(sheetname "Supervisior MCU")
		(sheetfile "supervisor-mcu.kicad_sch")
		(attr smd)
		(fp_line
			(start -0.8 -0.45)
			(end -0.8 0.45)
			(stroke
				(width 0.12)
				(type solid)
			)
			(layer "F.SilkS")
		)
		(fp_line
			(start 0.8 -0.45)
			(end 0.8 0.45)
			(stroke
				(width 0.12)
				(type solid)
			)
			(layer "F.SilkS")
		)
		(fp_rect
			(start -0.898 -0.66)
			(end 0.898 0.65)
			(stroke
				(width 0.05)
				(type solid)
			)
			(fill no)
			(layer "F.CrtYd")
		)
		(pad "1" smd roundrect
			(at -0.6 0.298)
			(size 0.2 0.4)
			(layers "F.Cu" "F.Mask" "F.Paste")
			(roundrect_rratio 0.25)
			(net 1082 "/Supervisior MCU/TXD0")
			(pinfunction "R1.1")
			(pintype "passive")
		)
		(pad "2" smd roundrect
			(at -0.202 0.298)
			(size 0.2 0.4)
			(layers "F.Cu" "F.Mask" "F.Paste")
			(roundrect_rratio 0.25)
			(net 1081 "/Supervisior MCU/TXD1")
			(pinfunction "R2.1")
			(pintype "passive")
		)
		(pad "3" smd roundrect
			(at 0.2 0.298)
			(size 0.2 0.4)
			(layers "F.Cu" "F.Mask" "F.Paste")
			(roundrect_rratio 0.25)
			(net 1084 "/Supervisior MCU/RXD0")
			(pinfunction "R3.1")
			(pintype "passive")
		)
		(pad "4" smd roundrect
			(at 0.598 0.298)
			(size 0.2 0.4)
			(layers "F.Cu" "F.Mask" "F.Paste")
			(roundrect_rratio 0.25)
			(net 1087 "/Supervisior MCU/PGOOD_1V8")
			(pinfunction "R4.1")
			(pintype "passive")
		)
		(pad "5" smd roundrect
			(at 0.598 -0.3)
			(size 0.2 0.4)
			(layers "F.Cu" "F.Mask" "F.Paste")
			(roundrect_rratio 0.25)
			(net 1413 "/SUP_MCU.PG_1V2")
			(pinfunction "R4.2")
			(pintype "passive")
		)
		(pad "6" smd roundrect
			(at 0.2 -0.3)
			(size 0.2 0.4)
			(layers "F.Cu" "F.Mask" "F.Paste")
			(roundrect_rratio 0.25)
			(net 1331 "/SUP_MCU.RX0")
			(pinfunction "R3.2")
			(pintype "passive")
		)
		(pad "7" smd roundrect
			(at -0.202 -0.3)
			(size 0.2 0.4)
			(layers "F.Cu" "F.Mask" "F.Paste")
			(roundrect_rratio 0.25)
			(net 1328 "/SUP_MCU.TX1")
			(pinfunction "R2.2")
			(pintype "passive")
		)
		(pad "8" smd roundrect
			(at -0.6 -0.3)
			(size 0.2 0.4)
			(layers "F.Cu" "F.Mask" "F.Paste")
			(roundrect_rratio 0.25)
			(net 1329 "/SUP_MCU.TX0")
			(pinfunction "R1.2")
			(pintype "passive")
		)
	)
	(footprint "antmicro-footprints:C_0402_1005Metric"
		(layer "F.Cu")
		(at 226.7 147.5 90)
		(descr "Capacitor SMD 0402")
		(tags "capacitor SMD 0402")
		(property "Reference" "C271"
			(at 0.75 0.3 90)
			(layer "F.SilkS")
			(effects
				(font
					(size 0.7 0.7)
					(thickness 0.15)
				)
				(justify left bottom)
			)
		)
		(property "Value" "C_10u_0402"
			(at 0 1.4 90)
			(layer "F.Fab")
			(effects
				(font
					(size 0.7 0.7)
					(thickness 0.15)
				)
				(justify left bottom)
			)
		)
		(property "Description" "SMD Multilayer Ceramic Capacitor, 10 µF, 6.3 V, 0402 [1005 Metric], ± 20%, X5R, CC Series"
			(at 0 0 90)
			(layer "F.Fab")
			(hide yes)
			(effects
				(font
					(size 1.27 1.27)
					(thickness 0.15)
				)
			)
		)
		(property "Author" "Antmicro"
			(at 374.2 -79.2 0)
			(layer "F.Fab")
			(hide yes)
			(effects
				(font
					(size 1 1)
					(thickness 0.15)
				)
			)
		)
		(property "Dielectric" ""
			(at 374.2 -79.2 0)
			(layer "F.Fab")
			(hide yes)
			(effects
				(font
					(size 1 1)
					(thickness 0.15)
				)
			)
		)
		(property "License" "Apache-2.0"
			(at 374.2 -79.2 0)
			(layer "F.Fab")
			(hide yes)
			(effects
				(font
					(size 1 1)
					(thickness 0.15)
				)
			)
		)
		(property "MPN" "CC0402MRX5R5BB106"
			(at 374.2 -79.2 0)
			(layer "F.Fab")
			(hide yes)
			(effects
				(font
					(size 1 1)
					(thickness 0.15)
				)
			)
		)
		(property "Manufacturer" "YAGEO"
			(at 374.2 -79.2 0)
			(layer "F.Fab")
			(hide yes)
			(effects
				(font
					(size 1 1)
					(thickness 0.15)
				)
			)
		)
		(property "Val" "10u"
			(at 374.2 -79.2 0)
			(layer "F.Fab")
			(hide yes)
			(effects
				(font
					(size 1 1)
					(thickness 0.15)
				)
			)
		)
		(property "Voltage" ""
			(at 374.2 -79.2 0)
			(layer "F.Fab")
			(hide yes)
			(effects
				(font
					(size 1 1)
					(thickness 0.15)
				)
			)
		)
		(sheetname "HDMI + Ethernet")
		(sheetfile "hdmi-ethernet.kicad_sch")
		(attr smd)
		(fp_rect
			(start -0.925 -0.47)
			(end 0.925 0.47)
			(stroke
				(width 0.05)
				(type default)
			)
			(fill no)
			(layer "F.CrtYd")
		)
		(fp_line
			(start 0.504 -0.25)
			(end 0.504 0.248)
			(stroke
				(width 0.15)
				(type solid)
			)
			(layer "F.Fab")
		)
		(fp_line
			(start -0.494 -0.25)
			(end 0.504 -0.25)
			(stroke
				(width 0.15)
				(type solid)
			)
			(layer "F.Fab")
		)
		(fp_line
			(start 0.504 0.248)
			(end -0.494 0.248)
			(stroke
				(width 0.15)
				(type solid)
			)
			(layer "F.Fab")
		)
		(fp_line
			(start -0.494 0.248)
			(end -0.494 -0.25)
			(stroke
				(width 0.15)
				(type solid)
			)
			(layer "F.Fab")
		)
		(pad "1" smd roundrect
			(at -0.48 0 90)
			(size 0.59 0.64)
			(layers "F.Cu" "F.Mask" "F.Paste")
			(roundrect_rratio 0.25)
			(net 722 "/HDMI + Ethernet/ETH_VDDCR")
			(pintype "passive")
		)
		(pad "2" smd roundrect
			(at 0.48 0 90)
			(size 0.59 0.64)
			(layers "F.Cu" "F.Mask" "F.Paste")
			(roundrect_rratio 0.25)
			(net 1 "GND")
			(pintype "passive")
		)
	)
	(footprint "antmicro-footprints:C_0402_1005Metric"
		(layer "F.Cu")
		(at 164.7 140)
		(descr "Capacitor SMD 0402")
		(tags "capacitor SMD 0402")
		(property "Reference" "C391"
			(at -0.95 -1.5 0)
			(layer "F.SilkS")
			(effects
				(font
					(size 0.7 0.7)
					(thickness 0.15)
				)
				(justify left bottom)
			)
		)
		(property "Value" "C_100n_0402"
			(at 0 1.169 0)
			(layer "F.Fab")
			(effects
				(font
					(size 0.7 0.7)
					(thickness 0.15)
				)
				(justify left bottom)
			)
		)
		(property "Description" "SMD Multilayer Ceramic Capacitor, 0.1 µF, 50 V, 0402 [1005 Metric], ± 10%, X5R, GRM Series"
			(at 0 0 0)
			(layer "F.Fab")
			(hide yes)
			(effects
				(font
					(size 1.27 1.27)
					(thickness 0.15)
				)
			)
		)
		(property "Author" "Antmicro"
			(at 0 0 0)
			(layer "F.Fab")
			(hide yes)
			(effects
				(font
					(size 1 1)
					(thickness 0.15)
				)
			)
		)
		(property "Dielectric" "X5R"
			(at 0 0 0)
			(layer "F.Fab")
			(hide yes)
			(effects
				(font
					(size 1 1)
					(thickness 0.15)
				)
			)
		)
		(property "License" "Apache-2.0"
			(at 0 0 0)
			(layer "F.Fab")
			(hide yes)
			(effects
				(font
					(size 1 1)
					(thickness 0.15)
				)
			)
		)
		(property "MPN" "GRM155R61H104KE14D"
			(at 0 0 0)
			(layer "F.Fab")
			(hide yes)
			(effects
				(font
					(size 1 1)
					(thickness 0.15)
				)
			)
		)
		(property "Manufacturer" "Murata"
			(at 0 0 0)
			(layer "F.Fab")
			(hide yes)
			(effects
				(font
					(size 1 1)
					(thickness 0.15)
				)
			)
		)
		(property "Val" "100n"
			(at 0 0 0)
			(layer "F.Fab")
			(hide yes)
			(effects
				(font
					(size 1 1)
					(thickness 0.15)
				)
			)
		)
		(property "Voltage" "50V"
			(at 0 0 0)
			(layer "F.Fab")
			(hide yes)
			(effects
				(font
					(size 1 1)
					(thickness 0.15)
				)
			)
		)
		(sheetname "DRAM + SRAM")
		(sheetfile "ram.kicad_sch")
		(attr smd)
		(fp_rect
			(start -0.925 -0.47)
			(end 0.925 0.47)
			(stroke
				(width 0.05)
				(type default)
			)
			(fill no)
			(layer "F.CrtYd")
		)
		(fp_line
			(start -0.494 -0.25)
			(end 0.504 -0.25)
			(stroke
				(width 0.15)
				(type solid)
			)
			(layer "F.Fab")
		)
		(fp_line
			(start -0.494 0.248)
			(end -0.494 -0.25)
			(stroke
				(width 0.15)
				(type solid)
			)
			(layer "F.Fab")
		)
		(fp_line
			(start 0.504 -0.25)
			(end 0.504 0.248)
			(stroke
				(width 0.15)
				(type solid)
			)
			(layer "F.Fab")
		)
		(fp_line
			(start 0.504 0.248)
			(end -0.494 0.248)
			(stroke
				(width 0.15)
				(type solid)
			)
			(layer "F.Fab")
		)
		(pad "1" smd roundrect
			(at -0.48 0)
			(size 0.59 0.64)
			(layers "F.Cu" "F.Mask" "F.Paste")
			(roundrect_rratio 0.25)
			(net 1 "GND")
			(pintype "passive")
		)
		(pad "2" smd roundrect
			(at 0.48 0)
			(size 0.59 0.64)
			(layers "F.Cu" "F.Mask" "F.Paste")
			(roundrect_rratio 0.25)
			(net 25 "+1V35")
			(pintype "passive")
		)
	)
	(footprint "antmicro-footprints:R_0402_1005Metric"
		(layer "F.Cu")
		(at 179.5 175.7125)
		(descr "Resistor SMD 0402")
		(tags "resistor SMD 0402")
		(property "Reference" "R313"
			(at -1.775 1.2375 0)
			(layer "F.SilkS")
			(effects
				(font
					(size 0.7 0.7)
					(thickness 0.15)
				)
				(justify left bottom)
			)
		)
		(property "Value" "R_0R_0402"
			(at 0 1.4 0)
			(layer "F.Fab")
			(effects
				(font
					(size 0.7 0.7)
					(thickness 0.15)
				)
				(justify left bottom)
			)
		)
		(property "Description" "SMD Chip Resistor, Jumper, 0 ohm, 100 mW, 0402 [1005 Metric], Thick Film, General Purpose"
			(at 0 0 0)
			(layer "F.Fab")
			(hide yes)
			(effects
				(font
					(size 1.27 1.27)
					(thickness 0.15)
				)
			)
		)
		(property "Author" "Antmicro"
			(at 0 0 0)
			(layer "F.Fab")
			(hide yes)
			(effects
				(font
					(size 1 1)
					(thickness 0.15)
				)
			)
		)
		(property "Current" "1A"
			(at 0 0 0)
			(layer "F.Fab")
			(hide yes)
			(effects
				(font
					(size 1 1)
					(thickness 0.15)
				)
			)
		)
		(property "License" "Apache-2.0"
			(at 0 0 0)
			(layer "F.Fab")
			(hide yes)
			(effects
				(font
					(size 1 1)
					(thickness 0.15)
				)
			)
		)
		(property "MPN" "ERJ2GE0R00X"
			(at 0 0 0)
			(layer "F.Fab")
			(hide yes)
			(effects
				(font
					(size 1 1)
					(thickness 0.15)
				)
			)
		)
		(property "Manufacturer" "Panasonic"
			(at 0 0 0)
			(layer "F.Fab")
			(hide yes)
			(effects
				(font
					(size 1 1)
					(thickness 0.15)
				)
			)
		)
		(property "Tolerance" ""
			(at 0 0 0)
			(layer "F.Fab")
			(hide yes)
			(effects
				(font
					(size 1 1)
					(thickness 0.15)
				)
			)
		)
		(property "Val" "0R"
			(at 0 0 0)
			(layer "F.Fab")
			(hide yes)
			(effects
				(font
					(size 1 1)
					(thickness 0.15)
				)
			)
		)
		(sheetname "DC-DC Converters")
		(sheetfile "dc-dc.kicad_sch")
		(attr smd)
		(fp_rect
			(start -0.925 -0.47)
			(end 0.925 0.47)
			(stroke
				(width 0.05)
				(type default)
			)
			(fill no)
			(layer "F.CrtYd")
		)
		(fp_rect
			(start -0.5 -0.25)
			(end 0.5 0.25)
			(stroke
				(width 0.15)
				(type solid)
			)
			(fill no)
			(layer "F.Fab")
		)
		(pad "1" smd roundrect
			(at -0.48 0)
			(size 0.59 0.64)
			(layers "F.Cu" "F.Mask" "F.Paste")
			(roundrect_rratio 0.25)
			(net 964 "/DC-DC Converters/FB7")
			(pintype "passive")
		)
		(pad "2" smd roundrect
			(at 0.48 0)
			(size 0.59 0.64)
			(layers "F.Cu" "F.Mask" "F.Paste")
			(roundrect_rratio 0.25)
			(net 739 "/DC-DC Converters/5V_local")
			(pintype "passive")
		)
	)
	(footprint "antmicro-footprints:C_0402_1005Metric"
		(layer "F.Cu")
		(at 188.501 148.8 180)
		(descr "Capacitor SMD 0402")
		(tags "capacitor SMD 0402")
		(property "Reference" "C370"
			(at -0.949 0.5 0)
			(layer "F.SilkS")
			(effects
				(font
					(size 0.7 0.7)
					(thickness 0.15)
				)
				(justify right bottom)
			)
		)
		(property "Value" "C_100n_0402"
			(at 0 1.4 0)
			(layer "F.Fab")
			(effects
				(font
					(size 0.7 0.7)
					(thickness 0.15)
				)
				(justify right bottom)
			)
		)
		(property "Description" "SMD Multilayer Ceramic Capacitor, 0.1 µF, 50 V, 0402 [1005 Metric], ± 10%, X5R, GRM Series"
			(at 0 0 180)
			(layer "F.Fab")
			(hide yes)
			(effects
				(font
					(size 1.27 1.27)
					(thickness 0.15)
				)
			)
		)
		(property "Author" "Antmicro"
			(at 377.002 297.6 0)
			(layer "F.Fab")
			(hide yes)
			(effects
				(font
					(size 1 1)
					(thickness 0.15)
				)
			)
		)
		(property "Dielectric" "X5R"
			(at 377.002 297.6 0)
			(layer "F.Fab")
			(hide yes)
			(effects
				(font
					(size 1 1)
					(thickness 0.15)
				)
			)
		)
		(property "License" "Apache-2.0"
			(at 377.002 297.6 0)
			(layer "F.Fab")
			(hide yes)
			(effects
				(font
					(size 1 1)
					(thickness 0.15)
				)
			)
		)
		(property "MPN" "GRM155R61H104KE14D"
			(at 377.002 297.6 0)
			(layer "F.Fab")
			(hide yes)
			(effects
				(font
					(size 1 1)
					(thickness 0.15)
				)
			)
		)
		(property "Manufacturer" "Murata"
			(at 377.002 297.6 0)
			(layer "F.Fab")
			(hide yes)
			(effects
				(font
					(size 1 1)
					(thickness 0.15)
				)
			)
		)
		(property "Val" "100n"
			(at 377.002 297.6 0)
			(layer "F.Fab")
			(hide yes)
			(effects
				(font
					(size 1 1)
					(thickness 0.15)
				)
			)
		)
		(property "Voltage" "50V"
			(at 377.002 297.6 0)
			(layer "F.Fab")
			(hide yes)
			(effects
				(font
					(size 1 1)
					(thickness 0.15)
				)
			)
		)
		(sheetname "Clocks")
		(sheetfile "clocks.kicad_sch")
		(attr smd)
		(fp_rect
			(start -0.925 -0.47)
			(end 0.925 0.47)
			(stroke
				(width 0.05)
				(type default)
			)
			(fill no)
			(layer "F.CrtYd")
		)
		(fp_line
			(start 0.504 0.248)
			(end -0.494 0.248)
			(stroke
				(width 0.15)
				(type solid)
			)
			(layer "F.Fab")
		)
		(fp_line
			(start 0.504 -0.25)
			(end 0.504 0.248)
			(stroke
				(width 0.15)
				(type solid)
			)
			(layer "F.Fab")
		)
		(fp_line
			(start -0.494 0.248)
			(end -0.494 -0.25)
			(stroke
				(width 0.15)
				(type solid)
			)
			(layer "F.Fab")
		)
		(fp_line
			(start -0.494 -0.25)
			(end 0.504 -0.25)
			(stroke
				(width 0.15)
				(type solid)
			)
			(layer "F.Fab")
		)
		(pad "1" smd roundrect
			(at -0.48 0 180)
			(size 0.59 0.64)
			(layers "F.Cu" "F.Mask" "F.Paste")
			(roundrect_rratio 0.25)
			(net 1 "GND")
			(pintype "passive")
		)
		(pad "2" smd roundrect
			(at 0.48 0 180)
			(size 0.59 0.64)
			(layers "F.Cu" "F.Mask" "F.Paste")
			(roundrect_rratio 0.25)
			(net 26 "+1V8")
			(pintype "passive")
		)
	)
	(footprint "antmicro-footprints:R_0402_1005Metric"
		(layer "F.Cu")
		(at 242.15 106.1)
		(descr "Resistor SMD 0402")
		(tags "resistor SMD 0402")
		(property "Reference" "R256"
			(at -3.65 0.35 0)
			(layer "F.SilkS")
			(effects
				(font
					(size 0.7 0.7)
					(thickness 0.15)
				)
				(justify left bottom)
			)
		)
		(property "Value" "R_0R_0402"
			(at 0 1.4 0)
			(layer "F.Fab")
			(effects
				(font
					(size 0.7 0.7)
					(thickness 0.15)
				)
				(justify left bottom)
			)
		)
		(property "Description" "SMD Chip Resistor, Jumper, 0 ohm, 100 mW, 0402 [1005 Metric], Thick Film, General Purpose"
			(at 0 0 0)
			(layer "F.Fab")
			(hide yes)
			(effects
				(font
					(size 1.27 1.27)
					(thickness 0.15)
				)
			)
		)
		(property "Author" "Antmicro"
			(at 0 0 0)
			(layer "F.Fab")
			(hide yes)
			(effects
				(font
					(size 1 1)
					(thickness 0.15)
				)
			)
		)
		(property "Current" "1A"
			(at 0 0 0)
			(layer "F.Fab")
			(hide yes)
			(effects
				(font
					(size 1 1)
					(thickness 0.15)
				)
			)
		)
		(property "License" "Apache-2.0"
			(at 0 0 0)
			(layer "F.Fab")
			(hide yes)
			(effects
				(font
					(size 1 1)
					(thickness 0.15)
				)
			)
		)
		(property "MPN" "ERJ2GE0R00X"
			(at 0 0 0)
			(layer "F.Fab")
			(hide yes)
			(effects
				(font
					(size 1 1)
					(thickness 0.15)
				)
			)
		)
		(property "Manufacturer" "Panasonic"
			(at 0 0 0)
			(layer "F.Fab")
			(hide yes)
			(effects
				(font
					(size 1 1)
					(thickness 0.15)
				)
			)
		)
		(property "Tolerance" ""
			(at 0 0 0)
			(layer "F.Fab")
			(hide yes)
			(effects
				(font
					(size 1 1)
					(thickness 0.15)
				)
			)
		)
		(property "Val" "0R"
			(at 0 0 0)
			(layer "F.Fab")
			(hide yes)
			(effects
				(font
					(size 1 1)
					(thickness 0.15)
				)
			)
		)
		(sheetname "HDMI + Ethernet")
		(sheetfile "hdmi-ethernet.kicad_sch")
		(attr smd)
		(fp_rect
			(start -0.925 -0.47)
			(end 0.925 0.47)
			(stroke
				(width 0.05)
				(type default)
			)
			(fill no)
			(layer "F.CrtYd")
		)
		(fp_rect
			(start -0.5 -0.25)
			(end 0.5 0.25)
			(stroke
				(width 0.15)
				(type solid)
			)
			(fill no)
			(layer "F.Fab")
		)
		(pad "1" smd roundrect
			(at -0.48 0)
			(size 0.59 0.64)
			(layers "F.Cu" "F.Mask" "F.Paste")
			(roundrect_rratio 0.25)
			(net 526 "/FPGA Bank 16 & 17/HDMI.D1_P")
			(pintype "passive")
		)
		(pad "2" smd roundrect
			(at 0.48 0)
			(size 0.59 0.64)
			(layers "F.Cu" "F.Mask" "F.Paste")
			(roundrect_rratio 0.25)
			(net 865 "/HDMI + Ethernet/HDMI_CONN_D1_P")
			(pintype "passive")
		)
	)
)
